(kicad_pcb
	(version 20260206)
	(generator "pcbnew")
	(generator_version "10.0")
	(general
		(thickness 1.6)
		(legacy_teardrops no)
	)
	(paper "A4")
	(title_block
		(title "04192023_DAF0TMB3IC0_F0TG_MB_C_brd_V02_OCP.brd")
		(comment 1 "Grand Teton / footprints 4539-4546 of 8354")
	)
	(layers
		(0 "F.Cu" signal "TOP")
		(4 "In1.Cu" signal "GND")
		(6 "In2.Cu" signal "IN1")
		(8 "In3.Cu" signal "GND1")
		(10 "In4.Cu" signal "IN2")
		(12 "In5.Cu" signal "GND2")
		(14 "In6.Cu" signal "IN3")
		(16 "In7.Cu" signal "GND3")
		(18 "In8.Cu" signal "VCC")
		(20 "In9.Cu" signal "VCC1")
		(22 "In10.Cu" signal "GND4")
		(24 "In11.Cu" signal "IN4")
		(26 "In12.Cu" signal "GND5")
		(28 "In13.Cu" signal "IN5")
		(30 "In14.Cu" signal "GND6")
		(32 "In15.Cu" signal "IN6")
		(34 "In16.Cu" signal "GND7")
		(2 "B.Cu" signal "BOTTOM")
		(9 "F.Adhes" user "F.Adhesive")
		(11 "B.Adhes" user "B.Adhesive")
		(13 "F.Paste" user "Package Geometry/Pastemask Top")
		(15 "B.Paste" user "Package Geometry/Pastemask Bottom")
		(5 "F.SilkS" user "Ref Des/Silkscreen Top")
		(7 "B.SilkS" user "Ref Des/Silkscreen Bottom")
		(1 "F.Mask" user "Board Geometry/Soldermask Top")
		(3 "B.Mask" user "Board Geometry/Soldermask Bottom")
		(17 "Dwgs.User" user "User.Drawings")
		(19 "Cmts.User" user "User.Comments")
		(21 "Eco1.User" user "User.Eco1")
		(23 "Eco2.User" user "User.Eco2")
		(25 "Edge.Cuts" user "Board Geometry/Outline")
		(27 "Margin" user)
		(31 "F.CrtYd" user "Package Geometry/Place Bound Top")
		(29 "B.CrtYd" user "Package Geometry/Place Bound Bottom")
		(35 "F.Fab" user "Ref Des/Assembly Top")
		(33 "B.Fab" user "Ref Des/Assembly Bottom")
	)
	(footprint ""
		(layer "F.Cu")
		(at 412.75 -98.425 -90)
		(property "Reference" "R8094"
			(at 0 0 270)
			(layer "F.SilkS")
			(hide yes)
			(effects
				(font
					(size 1.27 1.27)
				)
			)
		)
		(property "Value" ""
			(at 0 0 270)
			(layer "F.Fab")
			(effects
				(font
					(size 1.27 1.27)
				)
			)
		)
		(duplicate_pad_numbers_are_jumpers no)
		(fp_line
			(start -0.7874 0.4064)
			(end -0.7874 -0.4064)
			(stroke
				(width 0.1524)
				(type default)
			)
			(layer "F.SilkS")
		)
		(fp_line
			(start 0.7874 0.4064)
			(end -0.7874 0.4064)
			(stroke
				(width 0.1524)
				(type default)
			)
			(layer "F.SilkS")
		)
		(fp_line
			(start -0.7874 -0.4064)
			(end 0.7874 -0.4064)
			(stroke
				(width 0.1524)
				(type default)
			)
			(layer "F.SilkS")
		)
		(fp_line
			(start 0.7874 -0.4064)
			(end 0.7874 0.4064)
			(stroke
				(width 0.1524)
				(type default)
			)
			(layer "F.SilkS")
		)
		(fp_line
			(start -0.67945 0.3048)
			(end -0.67945 -0.305054)
			(stroke
				(width 0.1)
				(type default)
			)
			(layer "F.Fab")
		)
		(fp_line
			(start -0.12065 0.3048)
			(end -0.67945 0.3048)
			(stroke
				(width 0.1)
				(type default)
			)
			(layer "F.Fab")
		)
		(fp_line
			(start 0.120396 0.3048)
			(end 0.120396 0.2794)
			(stroke
				(width 0.1)
				(type default)
			)
			(layer "F.Fab")
		)
		(fp_line
			(start 0.67945 0.3048)
			(end 0.120396 0.3048)
			(stroke
				(width 0.1)
				(type default)
			)
			(layer "F.Fab")
		)
		(fp_line
			(start -0.12065 0.2794)
			(end -0.12065 0.3048)
			(stroke
				(width 0.1)
				(type default)
			)
			(layer "F.Fab")
		)
		(fp_line
			(start 0.120396 0.2794)
			(end -0.12065 0.2794)
			(stroke
				(width 0.1)
				(type default)
			)
			(layer "F.Fab")
		)
		(fp_line
			(start -0.12065 -0.2794)
			(end 0.12065 -0.2794)
			(stroke
				(width 0.1)
				(type default)
			)
			(layer "F.Fab")
		)
		(fp_line
			(start 0.12065 -0.2794)
			(end 0.12065 -0.3048)
			(stroke
				(width 0.1)
				(type default)
			)
			(layer "F.Fab")
		)
		(fp_line
			(start 0.12065 -0.3048)
			(end 0.67945 -0.3048)
			(stroke
				(width 0.1)
				(type default)
			)
			(layer "F.Fab")
		)
		(fp_line
			(start 0.67945 -0.3048)
			(end 0.67945 0.3048)
			(stroke
				(width 0.1)
				(type default)
			)
			(layer "F.Fab")
		)
		(fp_line
			(start -0.67945 -0.305054)
			(end -0.12065 -0.305054)
			(stroke
				(width 0.1)
				(type default)
			)
			(layer "F.Fab")
		)
		(fp_line
			(start -0.12065 -0.305054)
			(end -0.12065 -0.2794)
			(stroke
				(width 0.1)
				(type default)
			)
			(layer "F.Fab")
		)
		(pad "1" smd circle
			(at -0.40005 0 270)
			(size 0 0)
			(layers "F.Cu" "F.Mask" "F.Paste")
			(net "OCP_V3_1_P3V3_R1_PWRGD")
		)
		(pad "2" smd circle
			(at 0.40005 0 270)
			(size 0 0)
			(layers "F.Cu" "F.Mask" "F.Paste")
			(net "OCP_V3_1_P3V3_PWRGD")
		)
	)
	(footprint ""
		(layer "F.Cu")
		(at 357.93426 -326.58431 180)
		(property "Reference" "PR49"
			(at 0 0 180)
			(layer "F.SilkS")
			(hide yes)
			(effects
				(font
					(size 1.27 1.27)
				)
			)
		)
		(property "Value" ""
			(at 0 0 180)
			(layer "F.Fab")
			(effects
				(font
					(size 1.27 1.27)
				)
			)
		)
		(duplicate_pad_numbers_are_jumpers no)
		(fp_line
			(start 0.7874 0.4064)
			(end -0.7874 0.4064)
			(stroke
				(width 0.1524)
				(type default)
			)
			(layer "F.SilkS")
		)
		(fp_line
			(start 0.7874 -0.4064)
			(end 0.7874 0.4064)
			(stroke
				(width 0.1524)
				(type default)
			)
			(layer "F.SilkS")
		)
		(fp_line
			(start -0.7874 0.4064)
			(end -0.7874 -0.4064)
			(stroke
				(width 0.1524)
				(type default)
			)
			(layer "F.SilkS")
		)
		(fp_line
			(start -0.7874 -0.4064)
			(end 0.7874 -0.4064)
			(stroke
				(width 0.1524)
				(type default)
			)
			(layer "F.SilkS")
		)
		(fp_line
			(start 0.67945 0.3048)
			(end 0.120396 0.3048)
			(stroke
				(width 0.1)
				(type default)
			)
			(layer "F.Fab")
		)
		(fp_line
			(start 0.67945 -0.3048)
			(end 0.67945 0.3048)
			(stroke
				(width 0.1)
				(type default)
			)
			(layer "F.Fab")
		)
		(fp_line
			(start 0.12065 -0.2794)
			(end 0.12065 -0.3048)
			(stroke
				(width 0.1)
				(type default)
			)
			(layer "F.Fab")
		)
		(fp_line
			(start 0.12065 -0.3048)
			(end 0.67945 -0.3048)
			(stroke
				(width 0.1)
				(type default)
			)
			(layer "F.Fab")
		)
		(fp_line
			(start 0.120396 0.3048)
			(end 0.120396 0.2794)
			(stroke
				(width 0.1)
				(type default)
			)
			(layer "F.Fab")
		)
		(fp_line
			(start 0.120396 0.2794)
			(end -0.12065 0.2794)
			(stroke
				(width 0.1)
				(type default)
			)
			(layer "F.Fab")
		)
		(fp_line
			(start -0.12065 0.3048)
			(end -0.67945 0.3048)
			(stroke
				(width 0.1)
				(type default)
			)
			(layer "F.Fab")
		)
		(fp_line
			(start -0.12065 0.2794)
			(end -0.12065 0.3048)
			(stroke
				(width 0.1)
				(type default)
			)
			(layer "F.Fab")
		)
		(fp_line
			(start -0.12065 -0.2794)
			(end 0.12065 -0.2794)
			(stroke
				(width 0.1)
				(type default)
			)
			(layer "F.Fab")
		)
		(fp_line
			(start -0.12065 -0.305054)
			(end -0.12065 -0.2794)
			(stroke
				(width 0.1)
				(type default)
			)
			(layer "F.Fab")
		)
		(fp_line
			(start -0.67945 0.3048)
			(end -0.67945 -0.305054)
			(stroke
				(width 0.1)
				(type default)
			)
			(layer "F.Fab")
		)
		(fp_line
			(start -0.67945 -0.305054)
			(end -0.12065 -0.305054)
			(stroke
				(width 0.1)
				(type default)
			)
			(layer "F.Fab")
		)
		(pad "1" smd circle
			(at -0.40005 0 180)
			(size 0 0)
			(layers "F.Cu" "F.Mask" "F.Paste")
			(net "VSENSE_VSS_SENSE_C_P0")
		)
		(pad "2" smd circle
			(at 0.40005 0 180)
			(size 0 0)
			(layers "F.Cu" "F.Mask" "F.Paste")
			(net "GND")
		)
	)
	(footprint ""
		(layer "F.Cu")
		(at 302.133 -358.14 180)
		(property "Reference" "C304"
			(at 0 0 180)
			(layer "F.SilkS")
			(hide yes)
			(effects
				(font
					(size 1.27 1.27)
				)
			)
		)
		(property "Value" ""
			(at 0 0 180)
			(layer "F.Fab")
			(effects
				(font
					(size 1.27 1.27)
				)
			)
		)
		(duplicate_pad_numbers_are_jumpers no)
		(fp_line
			(start 0.7874 0.4064)
			(end -0.7874 0.4064)
			(stroke
				(width 0.1524)
				(type default)
			)
			(layer "F.SilkS")
		)
		(fp_line
			(start 0.7874 -0.4064)
			(end 0.7874 0.4064)
			(stroke
				(width 0.1524)
				(type default)
			)
			(layer "F.SilkS")
		)
		(fp_line
			(start -0.7874 0.4064)
			(end -0.7874 -0.4064)
			(stroke
				(width 0.1524)
				(type default)
			)
			(layer "F.SilkS")
		)
		(fp_line
			(start -0.7874 -0.4064)
			(end 0.7874 -0.4064)
			(stroke
				(width 0.1524)
				(type default)
			)
			(layer "F.SilkS")
		)
		(fp_line
			(start 0.67945 0.3048)
			(end 0.120396 0.3048)
			(stroke
				(width 0.1)
				(type default)
			)
			(layer "F.Fab")
		)
		(fp_line
			(start 0.67945 -0.3048)
			(end 0.67945 0.3048)
			(stroke
				(width 0.1)
				(type default)
			)
			(layer "F.Fab")
		)
		(fp_line
			(start 0.12065 -0.2794)
			(end 0.12065 -0.3048)
			(stroke
				(width 0.1)
				(type default)
			)
			(layer "F.Fab")
		)
		(fp_line
			(start 0.12065 -0.3048)
			(end 0.67945 -0.3048)
			(stroke
				(width 0.1)
				(type default)
			)
			(layer "F.Fab")
		)
		(fp_line
			(start 0.120396 0.3048)
			(end 0.120396 0.2794)
			(stroke
				(width 0.1)
				(type default)
			)
			(layer "F.Fab")
		)
		(fp_line
			(start 0.120396 0.2794)
			(end -0.12065 0.2794)
			(stroke
				(width 0.1)
				(type default)
			)
			(layer "F.Fab")
		)
		(fp_line
			(start -0.12065 0.3048)
			(end -0.67945 0.3048)
			(stroke
				(width 0.1)
				(type default)
			)
			(layer "F.Fab")
		)
		(fp_line
			(start -0.12065 0.2794)
			(end -0.12065 0.3048)
			(stroke
				(width 0.1)
				(type default)
			)
			(layer "F.Fab")
		)
		(fp_line
			(start -0.12065 -0.2794)
			(end 0.12065 -0.2794)
			(stroke
				(width 0.1)
				(type default)
			)
			(layer "F.Fab")
		)
		(fp_line
			(start -0.12065 -0.305054)
			(end -0.12065 -0.2794)
			(stroke
				(width 0.1)
				(type default)
			)
			(layer "F.Fab")
		)
		(fp_line
			(start -0.67945 0.3048)
			(end -0.67945 -0.305054)
			(stroke
				(width 0.1)
				(type default)
			)
			(layer "F.Fab")
		)
		(fp_line
			(start -0.67945 -0.305054)
			(end -0.12065 -0.305054)
			(stroke
				(width 0.1)
				(type default)
			)
			(layer "F.Fab")
		)
		(pad "1" smd circle
			(at -0.40005 0 180)
			(size 0 0)
			(layers "F.Cu" "F.Mask" "F.Paste")
			(net "SVID_PVDDCR_CPU1_P0_SVD_R")
		)
		(pad "2" smd circle
			(at 0.40005 0 180)
			(size 0 0)
			(layers "F.Cu" "F.Mask" "F.Paste")
			(net "GND")
		)
	)
	(footprint ""
		(layer "F.Cu")
		(at 111.004096 -373.03583 -90)
		(property "Reference" "C1542"
			(at 0 0 270)
			(layer "F.SilkS")
			(hide yes)
			(effects
				(font
					(size 1.27 1.27)
				)
			)
		)
		(property "Value" ""
			(at 0 0 270)
			(layer "F.Fab")
			(effects
				(font
					(size 1.27 1.27)
				)
			)
		)
		(duplicate_pad_numbers_are_jumpers no)
		(fp_line
			(start -0.299974 0.150114)
			(end -0.299974 -0.150114)
			(stroke
				(width 0.1)
				(type default)
			)
			(layer "F.Fab")
		)
		(fp_line
			(start 0.299974 0.150114)
			(end -0.299974 0.150114)
			(stroke
				(width 0.1)
				(type default)
			)
			(layer "F.Fab")
		)
		(fp_line
			(start -0.299974 -0.150114)
			(end 0.299974 -0.150114)
			(stroke
				(width 0.1)
				(type default)
			)
			(layer "F.Fab")
		)
		(fp_line
			(start 0.299974 -0.150114)
			(end 0.299974 0.150114)
			(stroke
				(width 0.1)
				(type default)
			)
			(layer "F.Fab")
		)
		(pad "1" smd rect
			(at -0.2667 0 270)
			(size 0.3048 0.381)
			(layers "F.Cu" "F.Mask" "F.Paste")
			(net "P5E_CPU1_P3_TX_C_DN<2>")
		)
		(pad "2" smd rect
			(at 0.2667 0 270)
			(size 0.3048 0.381)
			(layers "F.Cu" "F.Mask" "F.Paste")
			(net "P5E_CPU1_P3_TX_DN<2>")
		)
	)
	(footprint ""
		(layer "F.Cu")
		(at 142.437866 -408.517344 -90)
		(property "Reference" "C6712"
			(at 0 0 270)
			(layer "F.SilkS")
			(hide yes)
			(effects
				(font
					(size 1.27 1.27)
				)
			)
		)
		(property "Value" ""
			(at 0 0 270)
			(layer "F.Fab")
			(effects
				(font
					(size 1.27 1.27)
				)
			)
		)
		(duplicate_pad_numbers_are_jumpers no)
		(fp_line
			(start -0.299974 0.150114)
			(end -0.299974 -0.150114)
			(stroke
				(width 0.1)
				(type default)
			)
			(layer "F.Fab")
		)
		(fp_line
			(start 0.299974 0.150114)
			(end -0.299974 0.150114)
			(stroke
				(width 0.1)
				(type default)
			)
			(layer "F.Fab")
		)
		(fp_line
			(start -0.299974 -0.150114)
			(end 0.299974 -0.150114)
			(stroke
				(width 0.1)
				(type default)
			)
			(layer "F.Fab")
		)
		(fp_line
			(start 0.299974 -0.150114)
			(end 0.299974 0.150114)
			(stroke
				(width 0.1)
				(type default)
			)
			(layer "F.Fab")
		)
		(pad "1" smd rect
			(at -0.2667 0 270)
			(size 0.3048 0.381)
			(layers "F.Cu" "F.Mask" "F.Paste")
			(net "P5E_CPU1_P2_TX_BUF_C_DN<9>")
		)
		(pad "2" smd rect
			(at 0.2667 0 270)
			(size 0.3048 0.381)
			(layers "F.Cu" "F.Mask" "F.Paste")
			(net "P5E_CPU1_P2_TX_BUF_DN<9>")
		)
	)
	(footprint ""
		(layer "F.Cu")
		(at 11.7221 -394.22832 -90)
		(property "Reference" "PR6619"
			(at 0 0 270)
			(layer "F.SilkS")
			(hide yes)
			(effects
				(font
					(size 1.27 1.27)
				)
			)
		)
		(property "Value" ""
			(at 0 0 270)
			(layer "F.Fab")
			(effects
				(font
					(size 1.27 1.27)
				)
			)
		)
		(duplicate_pad_numbers_are_jumpers no)
		(fp_line
			(start -0.7874 0.4064)
			(end -0.7874 -0.4064)
			(stroke
				(width 0.1524)
				(type default)
			)
			(layer "F.SilkS")
		)
		(fp_line
			(start 0.7874 0.4064)
			(end -0.7874 0.4064)
			(stroke
				(width 0.1524)
				(type default)
			)
			(layer "F.SilkS")
		)
		(fp_line
			(start -0.7874 -0.4064)
			(end 0.7874 -0.4064)
			(stroke
				(width 0.1524)
				(type default)
			)
			(layer "F.SilkS")
		)
		(fp_line
			(start 0.7874 -0.4064)
			(end 0.7874 0.4064)
			(stroke
				(width 0.1524)
				(type default)
			)
			(layer "F.SilkS")
		)
		(fp_line
			(start -0.67945 0.3048)
			(end -0.67945 -0.305054)
			(stroke
				(width 0.1)
				(type default)
			)
			(layer "F.Fab")
		)
		(fp_line
			(start -0.12065 0.3048)
			(end -0.67945 0.3048)
			(stroke
				(width 0.1)
				(type default)
			)
			(layer "F.Fab")
		)
		(fp_line
			(start 0.120396 0.3048)
			(end 0.120396 0.2794)
			(stroke
				(width 0.1)
				(type default)
			)
			(layer "F.Fab")
		)
		(fp_line
			(start 0.67945 0.3048)
			(end 0.120396 0.3048)
			(stroke
				(width 0.1)
				(type default)
			)
			(layer "F.Fab")
		)
		(fp_line
			(start -0.12065 0.2794)
			(end -0.12065 0.3048)
			(stroke
				(width 0.1)
				(type default)
			)
			(layer "F.Fab")
		)
		(fp_line
			(start 0.120396 0.2794)
			(end -0.12065 0.2794)
			(stroke
				(width 0.1)
				(type default)
			)
			(layer "F.Fab")
		)
		(fp_line
			(start -0.12065 -0.2794)
			(end 0.12065 -0.2794)
			(stroke
				(width 0.1)
				(type default)
			)
			(layer "F.Fab")
		)
		(fp_line
			(start 0.12065 -0.2794)
			(end 0.12065 -0.3048)
			(stroke
				(width 0.1)
				(type default)
			)
			(layer "F.Fab")
		)
		(fp_line
			(start 0.12065 -0.3048)
			(end 0.67945 -0.3048)
			(stroke
				(width 0.1)
				(type default)
			)
			(layer "F.Fab")
		)
		(fp_line
			(start 0.67945 -0.3048)
			(end 0.67945 0.3048)
			(stroke
				(width 0.1)
				(type default)
			)
			(layer "F.Fab")
		)
		(fp_line
			(start -0.67945 -0.305054)
			(end -0.12065 -0.305054)
			(stroke
				(width 0.1)
				(type default)
			)
			(layer "F.Fab")
		)
		(fp_line
			(start -0.12065 -0.305054)
			(end -0.12065 -0.2794)
			(stroke
				(width 0.1)
				(type default)
			)
			(layer "F.Fab")
		)
		(pad "1" smd circle
			(at -0.40005 0 270)
			(size 0 0)
			(layers "F.Cu" "F.Mask" "F.Paste")
			(net "P5V_AUX")
		)
		(pad "2" smd circle
			(at 0.40005 0 270)
			(size 0 0)
			(layers "F.Cu" "F.Mask" "F.Paste")
			(net "P0V9_RETIMER_CPU1_PVCC")
		)
	)
	(footprint ""
		(layer "F.Cu")
		(at 375.513092 -378.95403 -90)
		(property "Reference" "C888"
			(at 0 0 270)
			(layer "F.SilkS")
			(hide yes)
			(effects
				(font
					(size 1.27 1.27)
				)
			)
		)
		(property "Value" ""
			(at 0 0 270)
			(layer "F.Fab")
			(effects
				(font
					(size 1.27 1.27)
				)
			)
		)
		(duplicate_pad_numbers_are_jumpers no)
		(fp_line
			(start -0.299974 0.150114)
			(end -0.299974 -0.150114)
			(stroke
				(width 0.1)
				(type default)
			)
			(layer "F.Fab")
		)
		(fp_line
			(start 0.299974 0.150114)
			(end -0.299974 0.150114)
			(stroke
				(width 0.1)
				(type default)
			)
			(layer "F.Fab")
		)
		(fp_line
			(start -0.299974 -0.150114)
			(end 0.299974 -0.150114)
			(stroke
				(width 0.1)
				(type default)
			)
			(layer "F.Fab")
		)
		(fp_line
			(start 0.299974 -0.150114)
			(end 0.299974 0.150114)
			(stroke
				(width 0.1)
				(type default)
			)
			(layer "F.Fab")
		)
		(pad "1" smd rect
			(at -0.2667 0 270)
			(size 0.3048 0.381)
			(layers "F.Cu" "F.Mask" "F.Paste")
			(net "P5E_CPU0_P3_TX_C_DN<6>")
		)
		(pad "2" smd rect
			(at 0.2667 0 270)
			(size 0.3048 0.381)
			(layers "F.Cu" "F.Mask" "F.Paste")
			(net "P5E_CPU0_P3_TX_DN<6>")
		)
	)
	(footprint ""
		(layer "F.Cu")
		(at 244.58803 -47.719234)
		(property "Reference" "R1323"
			(at 1.28397 -3.816096 0)
			(unlocked yes)
			(layer "F.SilkS")
			(effects
				(font
					(size 0.7874 0.5842)
					(thickness 0.1524)
				)
				(justify left)
			)
		)
		(property "Value" ""
			(at 0 0 0)
			(layer "F.Fab")
			(effects
				(font
					(size 1.27 1.27)
				)
			)
		)
		(duplicate_pad_numbers_are_jumpers no)
		(fp_line
			(start -3.937508 -1.8796)
			(end -3.937508 1.8796)
			(stroke
				(width 0.1524)
				(type default)
			)
			(layer "F.SilkS")
		)
		(fp_line
			(start -3.937508 1.8796)
			(end 3.937508 1.8796)
			(stroke
				(width 0.1524)
				(type default)
			)
			(layer "F.SilkS")
		)
		(fp_line
			(start 3.937508 -1.8796)
			(end -3.937508 -1.8796)
			(stroke
				(width 0.1524)
				(type default)
			)
			(layer "F.SilkS")
		)
		(fp_line
			(start 3.937508 1.8796)
			(end 3.937508 -1.8796)
			(stroke
				(width 0.1524)
				(type default)
			)
			(layer "F.SilkS")
		)
		(fp_line
			(start -3.275076 -1.674876)
			(end -3.275076 1.674876)
			(stroke
				(width 0.1)
				(type default)
			)
			(layer "F.Fab")
		)
		(fp_line
			(start -3.275076 1.674876)
			(end 3.275076 1.674876)
			(stroke
				(width 0.1)
				(type default)
			)
			(layer "F.Fab")
		)
		(fp_line
			(start 3.275076 -1.674876)
			(end -3.275076 -1.674876)
			(stroke
				(width 0.1)
				(type default)
			)
			(layer "F.Fab")
		)
		(fp_line
			(start 3.275076 1.674876)
			(end 3.275076 -1.674876)
			(stroke
				(width 0.1)
				(type default)
			)
			(layer "F.Fab")
		)
		(pad "1" smd rect
			(at -2.350008 0)
			(size 2.921 3.5052)
			(layers "F.Cu" "F.Mask" "F.Paste")
			(net "P12V_E1S_0_R")
		)
		(pad "2" smd rect
			(at 2.350008 0)
			(size 2.921 3.5052)
			(layers "F.Cu" "F.Mask" "F.Paste")
			(net "P12V_E1S_0")
		)
	)
)
